(kicad_pcb
	(version 20260206)
	(generator "pcbnew")
	(generator_version "10.0")
	(general
		(thickness 1.6)
		(legacy_teardrops no)
	)
	(paper "A4")
	(title_block
		(title "fcb — 12433-1M.1206WZS1330.brd")
		(comment 1 "Open Vault / Knox (Wiwynn) / footprints 352-357 of 495")
	)
	(layers
		(0 "F.Cu" signal "TOP")
		(4 "In1.Cu" signal "L2GND")
		(6 "In2.Cu" signal "L3VCC")
		(2 "B.Cu" signal "BOTTOM")
		(9 "F.Adhes" user "F.Adhesive")
		(11 "B.Adhes" user "B.Adhesive")
		(13 "F.Paste" user "Package Geometry/Pastemask Top")
		(15 "B.Paste" user "Package Geometry/Pastemask Bottom")
		(5 "F.SilkS" user "Ref Des/Silkscreen Top")
		(7 "B.SilkS" user "Ref Des/Silkscreen Bottom")
		(1 "F.Mask" user "Board Geometry/Soldermask Top")
		(3 "B.Mask" user "Board Geometry/Soldermask Bottom")
		(17 "Dwgs.User" user "User.Drawings")
		(19 "Cmts.User" user "User.Comments")
		(21 "Eco1.User" user "User.Eco1")
		(23 "Eco2.User" user "User.Eco2")
		(25 "Edge.Cuts" user "Board Geometry/Outline")
		(27 "Margin" user)
		(31 "F.CrtYd" user "Package Geometry/Place Bound Top")
		(29 "B.CrtYd" user "Package Geometry/Place Bound Bottom")
		(35 "F.Fab" user "Ref Des/Assembly Top")
		(33 "B.Fab" user "Ref Des/Assembly Bottom")
	)
	(footprint ""
		(layer "F.Cu")
		(at 15.494 -167.0304 90)
		(property "Reference" "C33"
			(at 0 0 90)
			(layer "F.SilkS")
			(hide yes)
			(effects
				(font
					(size 1.27 1.27)
				)
			)
		)
		(property "Value" "SCD1U50V3KX-GP"
			(at 0 -2.8194 90)
			(unlocked yes)
			(layer "F.Fab")
			(hide yes)
			(effects
				(font
					(size 1.016 1.016)
					(thickness 0.1524)
				)
			)
		)
		(property "Device Type" "C603H36"
			(at 0 -4.3434 90)
			(unlocked yes)
			(layer "F.Fab")
			(hide yes)
			(effects
				(font
					(size 1.016 1.016)
					(thickness 0.1524)
				)
			)
		)
		(duplicate_pad_numbers_are_jumpers no)
		(fp_line
			(start 0.508 0)
			(end -0.508 0)
			(stroke
				(width 0.2032)
				(type default)
			)
			(layer "F.SilkS")
		)
		(fp_rect
			(start -0.5842 1.3335)
			(end 0.5842 -1.3335)
			(stroke
				(width 0)
				(type default)
			)
			(fill no)
			(layer "F.CrtYd")
		)
		(fp_rect
			(start -0.5842 1.3335)
			(end 0.5842 -1.3335)
			(stroke
				(width 0)
				(type default)
			)
			(fill no)
			(layer "F.Fab")
		)
		(pad "1" smd custom
			(at 0 -0.762 90)
			(size 0.2159 0.2159)
			(layers "F.Cu" "F.Mask" "F.Paste")
			(net "P12V")
			(options
				(clearance outline)
				(anchor circle)
			)
			(primitives
				(gr_poly
					(pts
						(arc
							(start -0.3302 -0.4318)
							(mid -0.402042 -0.402042)
							(end -0.4318 -0.3302)
						)
						(arc
							(start -0.4318 0.3302)
							(mid -0.402042 0.402042)
							(end -0.3302 0.4318)
						)
						(arc
							(start 0.3302 0.4318)
							(mid 0.402042 0.402042)
							(end 0.4318 0.3302)
						)
						(arc
							(start 0.4318 -0.3302)
							(mid 0.402042 -0.402042)
							(end 0.3302 -0.4318)
						)
					)
					(width 0)
					(fill yes)
				)
			)
		)
		(pad "2" smd custom
			(at 0 0.762 90)
			(size 0.2159 0.2159)
			(layers "F.Cu" "F.Mask" "F.Paste")
			(net "GND")
			(options
				(clearance outline)
				(anchor circle)
			)
			(primitives
				(gr_poly
					(pts
						(arc
							(start -0.3302 -0.4318)
							(mid -0.402042 -0.402042)
							(end -0.4318 -0.3302)
						)
						(arc
							(start -0.4318 0.3302)
							(mid -0.402042 0.402042)
							(end -0.3302 0.4318)
						)
						(arc
							(start 0.3302 0.4318)
							(mid 0.402042 0.402042)
							(end 0.4318 0.3302)
						)
						(arc
							(start 0.4318 -0.3302)
							(mid 0.402042 -0.402042)
							(end 0.3302 -0.4318)
						)
					)
					(width 0)
					(fill yes)
				)
			)
		)
	)
	(footprint ""
		(layer "F.Cu")
		(at 28.582366 -242.327176)
		(property "Reference" "R42"
			(at 0 0 0)
			(layer "F.SilkS")
			(hide yes)
			(effects
				(font
					(size 1.27 1.27)
				)
			)
		)
		(property "Value" "4K7R2J-2-GP"
			(at 0.064008 -3.993896 0)
			(unlocked yes)
			(layer "F.Fab")
			(hide yes)
			(effects
				(font
					(size 1.016 1.016)
					(thickness 0.1524)
				)
			)
		)
		(property "Device Type" "R402H16"
			(at 0.064008 -5.517896 0)
			(unlocked yes)
			(layer "F.Fab")
			(hide yes)
			(effects
				(font
					(size 1.016 1.016)
					(thickness 0.1524)
				)
			)
		)
		(duplicate_pad_numbers_are_jumpers no)
		(fp_line
			(start -0.508 -0.9398)
			(end -0.508 0.9398)
			(stroke
				(width 0.1524)
				(type default)
			)
			(layer "F.SilkS")
		)
		(fp_line
			(start 0.508 -0.9398)
			(end -0.508 -0.9398)
			(stroke
				(width 0.1524)
				(type default)
			)
			(layer "F.SilkS")
		)
		(fp_rect
			(start -0.508 0.9398)
			(end 0.508 -0.9398)
			(stroke
				(width 0)
				(type default)
			)
			(fill no)
			(layer "F.CrtYd")
		)
		(fp_rect
			(start -0.508 0.9398)
			(end 0.508 -0.9398)
			(stroke
				(width 0)
				(type default)
			)
			(fill no)
			(layer "F.Fab")
		)
		(pad "1" smd custom
			(at 0 -0.4445)
			(size 0.1397 0.1397)
			(layers "F.Cu" "F.Mask" "F.Paste")
			(net "FCB_EEPROM_A0")
			(options
				(clearance outline)
				(anchor circle)
			)
			(primitives
				(gr_poly
					(pts
						(arc
							(start -0.1778 -0.2794)
							(mid -0.249642 -0.249642)
							(end -0.2794 -0.1778)
						)
						(arc
							(start -0.2794 0.1778)
							(mid -0.249642 0.249642)
							(end -0.1778 0.2794)
						)
						(arc
							(start 0.1778 0.2794)
							(mid 0.249642 0.249642)
							(end 0.2794 0.1778)
						)
						(arc
							(start 0.2794 -0.1778)
							(mid 0.249642 -0.249642)
							(end 0.1778 -0.2794)
						)
					)
					(width 0)
					(fill yes)
				)
			)
		)
		(pad "2" smd custom
			(at 0 0.4445)
			(size 0.1397 0.1397)
			(layers "F.Cu" "F.Mask" "F.Paste")
			(net "GND")
			(options
				(clearance outline)
				(anchor circle)
			)
			(primitives
				(gr_poly
					(pts
						(arc
							(start -0.1778 -0.2794)
							(mid -0.249642 -0.249642)
							(end -0.2794 -0.1778)
						)
						(arc
							(start -0.2794 0.1778)
							(mid -0.249642 0.249642)
							(end -0.1778 0.2794)
						)
						(arc
							(start 0.1778 0.2794)
							(mid 0.249642 0.249642)
							(end 0.2794 0.1778)
						)
						(arc
							(start 0.2794 -0.1778)
							(mid 0.249642 -0.249642)
							(end 0.1778 -0.2794)
						)
					)
					(width 0)
					(fill yes)
				)
			)
		)
	)
	(footprint ""
		(layer "F.Cu")
		(at 14.8844 -42.4942 -90)
		(property "Reference" "R173"
			(at 0 0 270)
			(layer "F.SilkS")
			(hide yes)
			(effects
				(font
					(size 1.27 1.27)
				)
			)
		)
		(property "Value" "0R2J-2-GP"
			(at 0.064008 -3.993896 270)
			(unlocked yes)
			(layer "F.Fab")
			(hide yes)
			(effects
				(font
					(size 1.016 1.016)
					(thickness 0.1524)
				)
			)
		)
		(property "Device Type" "R402H16"
			(at 0.064008 -5.517896 270)
			(unlocked yes)
			(layer "F.Fab")
			(hide yes)
			(effects
				(font
					(size 1.016 1.016)
					(thickness 0.1524)
				)
			)
		)
		(duplicate_pad_numbers_are_jumpers no)
		(fp_line
			(start -0.508 -0.9398)
			(end -0.508 0.9398)
			(stroke
				(width 0.1524)
				(type default)
			)
			(layer "F.SilkS")
		)
		(fp_line
			(start 0.508 -0.9398)
			(end -0.508 -0.9398)
			(stroke
				(width 0.1524)
				(type default)
			)
			(layer "F.SilkS")
		)
		(fp_rect
			(start -0.508 0.9398)
			(end 0.508 -0.9398)
			(stroke
				(width 0)
				(type default)
			)
			(fill no)
			(layer "F.CrtYd")
		)
		(fp_rect
			(start -0.508 0.9398)
			(end 0.508 -0.9398)
			(stroke
				(width 0)
				(type default)
			)
			(fill no)
			(layer "F.Fab")
		)
		(pad "1" smd custom
			(at 0 -0.4445 270)
			(size 0.1397 0.1397)
			(layers "F.Cu" "F.Mask" "F.Paste")
			(net "SELF_2B_HB")
			(options
				(clearance outline)
				(anchor circle)
			)
			(primitives
				(gr_poly
					(pts
						(arc
							(start -0.1778 -0.2794)
							(mid -0.249642 -0.249642)
							(end -0.2794 -0.1778)
						)
						(arc
							(start -0.2794 0.1778)
							(mid -0.249642 0.249642)
							(end -0.1778 0.2794)
						)
						(arc
							(start 0.1778 0.2794)
							(mid 0.249642 0.249642)
							(end 0.2794 0.1778)
						)
						(arc
							(start 0.2794 -0.1778)
							(mid 0.249642 -0.249642)
							(end 0.1778 -0.2794)
						)
					)
					(width 0)
					(fill yes)
				)
			)
		)
		(pad "2" smd custom
			(at 0 0.4445 270)
			(size 0.1397 0.1397)
			(layers "F.Cu" "F.Mask" "F.Paste")
			(net "SEB_PEER_1B_HB")
			(options
				(clearance outline)
				(anchor circle)
			)
			(primitives
				(gr_poly
					(pts
						(arc
							(start -0.1778 -0.2794)
							(mid -0.249642 -0.249642)
							(end -0.2794 -0.1778)
						)
						(arc
							(start -0.2794 0.1778)
							(mid -0.249642 0.249642)
							(end -0.1778 0.2794)
						)
						(arc
							(start 0.1778 0.2794)
							(mid 0.249642 0.249642)
							(end 0.2794 0.1778)
						)
						(arc
							(start 0.2794 -0.1778)
							(mid 0.249642 -0.249642)
							(end 0.1778 -0.2794)
						)
					)
					(width 0)
					(fill yes)
				)
			)
		)
	)
	(footprint ""
		(layer "F.Cu")
		(at 27.0764 -168.1988 -90)
		(property "Reference" "R164"
			(at 0 0 270)
			(layer "F.SilkS")
			(hide yes)
			(effects
				(font
					(size 1.27 1.27)
				)
			)
		)
		(property "Value" "0R2J-2-GP"
			(at 0.064008 -3.993896 270)
			(unlocked yes)
			(layer "F.Fab")
			(hide yes)
			(effects
				(font
					(size 1.016 1.016)
					(thickness 0.1524)
				)
			)
		)
		(property "Device Type" "R402H16"
			(at 0.064008 -5.517896 270)
			(unlocked yes)
			(layer "F.Fab")
			(hide yes)
			(effects
				(font
					(size 1.016 1.016)
					(thickness 0.1524)
				)
			)
		)
		(duplicate_pad_numbers_are_jumpers no)
		(fp_line
			(start -0.508 -0.9398)
			(end -0.508 0.9398)
			(stroke
				(width 0.1524)
				(type default)
			)
			(layer "F.SilkS")
		)
		(fp_line
			(start 0.508 -0.9398)
			(end -0.508 -0.9398)
			(stroke
				(width 0.1524)
				(type default)
			)
			(layer "F.SilkS")
		)
		(fp_rect
			(start -0.508 0.9398)
			(end 0.508 -0.9398)
			(stroke
				(width 0)
				(type default)
			)
			(fill no)
			(layer "F.CrtYd")
		)
		(fp_rect
			(start -0.508 0.9398)
			(end 0.508 -0.9398)
			(stroke
				(width 0)
				(type default)
			)
			(fill no)
			(layer "F.Fab")
		)
		(pad "1" smd custom
			(at 0 -0.4445 270)
			(size 0.1397 0.1397)
			(layers "F.Cu" "F.Mask" "F.Paste")
			(net "PWM_BUFFER_IN_FAN3_FAN4")
			(options
				(clearance outline)
				(anchor circle)
			)
			(primitives
				(gr_poly
					(pts
						(arc
							(start -0.1778 -0.2794)
							(mid -0.249642 -0.249642)
							(end -0.2794 -0.1778)
						)
						(arc
							(start -0.2794 0.1778)
							(mid -0.249642 0.249642)
							(end -0.1778 0.2794)
						)
						(arc
							(start 0.1778 0.2794)
							(mid 0.249642 0.249642)
							(end 0.2794 0.1778)
						)
						(arc
							(start 0.2794 -0.1778)
							(mid 0.249642 -0.249642)
							(end 0.1778 -0.2794)
						)
					)
					(width 0)
					(fill yes)
				)
			)
		)
		(pad "2" smd custom
			(at 0 0.4445 270)
			(size 0.1397 0.1397)
			(layers "F.Cu" "F.Mask" "F.Paste")
			(net "PWM_BUFFER_IN_FAN5_FAN6")
			(options
				(clearance outline)
				(anchor circle)
			)
			(primitives
				(gr_poly
					(pts
						(arc
							(start -0.1778 -0.2794)
							(mid -0.249642 -0.249642)
							(end -0.2794 -0.1778)
						)
						(arc
							(start -0.2794 0.1778)
							(mid -0.249642 0.249642)
							(end -0.1778 0.2794)
						)
						(arc
							(start 0.1778 0.2794)
							(mid 0.249642 0.249642)
							(end 0.2794 0.1778)
						)
						(arc
							(start 0.2794 -0.1778)
							(mid 0.249642 -0.249642)
							(end 0.1778 -0.2794)
						)
					)
					(width 0)
					(fill yes)
				)
			)
		)
	)
	(footprint ""
		(layer "F.Cu")
		(at 37.338 -144.272 -90)
		(property "Reference" "PR111"
			(at 0 0 270)
			(layer "F.SilkS")
			(hide yes)
			(effects
				(font
					(size 1.27 1.27)
				)
			)
		)
		(property "Value" "178KR2F-GP"
			(at 0.064008 -3.993896 270)
			(unlocked yes)
			(layer "F.Fab")
			(hide yes)
			(effects
				(font
					(size 1.016 1.016)
					(thickness 0.1524)
				)
			)
		)
		(property "Device Type" "R402H16"
			(at 0.064008 -5.517896 270)
			(unlocked yes)
			(layer "F.Fab")
			(hide yes)
			(effects
				(font
					(size 1.016 1.016)
					(thickness 0.1524)
				)
			)
		)
		(duplicate_pad_numbers_are_jumpers no)
		(fp_line
			(start -0.508 -0.9398)
			(end -0.508 0.9398)
			(stroke
				(width 0.1524)
				(type default)
			)
			(layer "F.SilkS")
		)
		(fp_line
			(start 0.508 -0.9398)
			(end -0.508 -0.9398)
			(stroke
				(width 0.1524)
				(type default)
			)
			(layer "F.SilkS")
		)
		(fp_rect
			(start -0.508 0.9398)
			(end 0.508 -0.9398)
			(stroke
				(width 0)
				(type default)
			)
			(fill no)
			(layer "F.CrtYd")
		)
		(fp_rect
			(start -0.508 0.9398)
			(end 0.508 -0.9398)
			(stroke
				(width 0)
				(type default)
			)
			(fill no)
			(layer "F.Fab")
		)
		(pad "1" smd custom
			(at 0 -0.4445 270)
			(size 0.1397 0.1397)
			(layers "F.Cu" "F.Mask" "F.Paste")
			(net "P12VL_2490_VREF")
			(options
				(clearance outline)
				(anchor circle)
			)
			(primitives
				(gr_poly
					(pts
						(arc
							(start -0.1778 -0.2794)
							(mid -0.249642 -0.249642)
							(end -0.2794 -0.1778)
						)
						(arc
							(start -0.2794 0.1778)
							(mid -0.249642 0.249642)
							(end -0.1778 0.2794)
						)
						(arc
							(start 0.1778 0.2794)
							(mid 0.249642 0.249642)
							(end 0.2794 0.1778)
						)
						(arc
							(start 0.2794 -0.1778)
							(mid 0.249642 -0.249642)
							(end 0.1778 -0.2794)
						)
					)
					(width 0)
					(fill yes)
				)
			)
		)
		(pad "2" smd custom
			(at 0 0.4445 270)
			(size 0.1397 0.1397)
			(layers "F.Cu" "F.Mask" "F.Paste")
			(net "P12VL_2490_PROG")
			(options
				(clearance outline)
				(anchor circle)
			)
			(primitives
				(gr_poly
					(pts
						(arc
							(start -0.1778 -0.2794)
							(mid -0.249642 -0.249642)
							(end -0.2794 -0.1778)
						)
						(arc
							(start -0.2794 0.1778)
							(mid -0.249642 0.249642)
							(end -0.1778 0.2794)
						)
						(arc
							(start 0.1778 0.2794)
							(mid 0.249642 0.249642)
							(end 0.2794 0.1778)
						)
						(arc
							(start 0.2794 -0.1778)
							(mid 0.249642 -0.249642)
							(end 0.1778 -0.2794)
						)
					)
					(width 0)
					(fill yes)
				)
			)
		)
	)
	(footprint ""
		(layer "F.Cu")
		(at 26.416 -410.591)
		(property "Reference" "PR30"
			(at 0 0 0)
			(layer "F.SilkS")
			(hide yes)
			(effects
				(font
					(size 1.27 1.27)
				)
			)
		)
		(property "Value" "D0005RL1632F-GP-U"
			(at 3.2258 1.2954 0)
			(unlocked yes)
			(layer "F.Fab")
			(hide yes)
			(effects
				(font
					(size 1.016 1.016)
					(thickness 0.1524)
				)
			)
		)
		(property "Device Type" "RL3115-4PH45"
			(at 3.2258 -0.2286 0)
			(unlocked yes)
			(layer "F.Fab")
			(hide yes)
			(effects
				(font
					(size 1.016 1.016)
					(thickness 0.1524)
				)
			)
		)
		(duplicate_pad_numbers_are_jumpers no)
		(fp_line
			(start -2.0574 -1.7653)
			(end -2.0574 -0.4064)
			(stroke
				(width 0.3302)
				(type default)
			)
			(layer "F.SilkS")
		)
		(fp_line
			(start -1.9685 -1.651)
			(end 1.9685 -1.651)
			(stroke
				(width 0.1524)
				(type default)
			)
			(layer "F.SilkS")
		)
		(fp_line
			(start -1.9685 1.651)
			(end -1.9685 -1.651)
			(stroke
				(width 0.1524)
				(type default)
			)
			(layer "F.SilkS")
		)
		(fp_line
			(start -0.5334 -1.7653)
			(end -2.0574 -1.7653)
			(stroke
				(width 0.3302)
				(type default)
			)
			(layer "F.SilkS")
		)
		(fp_line
			(start 1.9685 -1.651)
			(end 1.9685 1.651)
			(stroke
				(width 0.1524)
				(type default)
			)
			(layer "F.SilkS")
		)
		(fp_line
			(start 1.9685 1.651)
			(end -1.9685 1.651)
			(stroke
				(width 0.1524)
				(type default)
			)
			(layer "F.SilkS")
		)
		(fp_poly
			(pts
				(xy -0.561594 -1.726946) (xy -0.053594 -2.234946) (xy -1.069594 -2.234946)
			)
			(stroke
				(width 0)
				(type default)
			)
			(fill yes)
			(layer "F.SilkS")
		)
		(fp_rect
			(start -1.524 0.7493)
			(end 1.524 -0.7493)
			(stroke
				(width 0)
				(type default)
			)
			(fill no)
			(layer "F.CrtYd")
		)
		(fp_poly
			(pts
				(xy -2.2225 1.905) (xy -2.2225 -1.905) (xy 2.2225 -1.905) (xy 2.2225 -0.7493) (xy -1.524 -0.7493)
				(xy -1.524 0.7493) (xy 1.524 0.7493) (xy 1.524 -0.7366) (xy 2.2225 -0.7366) (xy 2.2225 1.905)
			)
			(stroke
				(width 0)
				(type default)
			)
			(fill no)
			(layer "F.CrtYd")
		)
		(fp_rect
			(start -2.2225 1.905)
			(end 2.2225 -1.905)
			(stroke
				(width 0)
				(type default)
			)
			(fill no)
			(layer "F.Fab")
		)
		(pad "1" smd rect
			(at -0.5715 -0.813562)
			(size 2.286 1.143)
			(layers "F.Cu" "F.Mask" "F.Paste")
			(net "P12V_AUX")
		)
		(pad "2" smd rect
			(at -0.5715 0.813562)
			(size 2.286 1.143)
			(layers "F.Cu" "F.Mask" "F.Paste")
			(net "P12V_SENSE_TRACE")
		)
		(pad "3" smd rect
			(at 1.334008 -0.813562)
			(size 0.762 1.143)
			(layers "F.Cu" "F.Mask" "F.Paste")
			(net "SENSE+_R2")
		)
		(pad "4" smd rect
			(at 1.334008 0.813562)
			(size 0.762 1.143)
			(layers "F.Cu" "F.Mask" "F.Paste")
			(net "SENSE-_R2")
		)
		(zone
			(layer "F.Cu")
			(hatch none 0.5)
			(connect_pads
				(clearance 0)
			)
			(min_thickness 0.25)
			(keepout
				(tracks not_allowed)
				(vias allowed)
				(pads allowed)
				(copperpour not_allowed)
				(footprints allowed)
			)
			(placement
				(enabled no)
				(sheetname "")
			)
			(fill
				(thermal_gap 0.5)
				(thermal_bridge_width 0.5)
				(island_removal_mode 0)
			)
			(polygon
				(pts
					(xy 26.9875 -410.833062) (xy 27.369008 -410.833062) (xy 27.369008 -411.3403) (xy 26.9875 -411.3403)
				)
			)
		)
		(zone
			(layer "F.Cu")
			(hatch none 0.5)
			(connect_pads
				(clearance 0)
			)
			(min_thickness 0.25)
			(keepout
				(tracks allowed)
				(vias not_allowed)
				(pads allowed)
				(copperpour not_allowed)
				(footprints allowed)
			)
			(placement
				(enabled no)
				(sheetname "")
			)
			(fill
				(thermal_gap 0.5)
				(thermal_bridge_width 0.5)
				(island_removal_mode 0)
			)
			(polygon
				(pts
					(xy 26.9875 -410.833062) (xy 27.369008 -410.833062) (xy 27.369008 -411.3403) (xy 26.9875 -411.3403)
				)
			)
		)
		(zone
			(layer "F.Cu")
			(hatch none 0.5)
			(connect_pads
				(clearance 0)
			)
			(min_thickness 0.25)
			(keepout
				(tracks allowed)
				(vias not_allowed)
				(pads allowed)
				(copperpour not_allowed)
				(footprints allowed)
			)
			(placement
				(enabled no)
				(sheetname "")
			)
			(fill
				(thermal_gap 0.5)
				(thermal_bridge_width 0.5)
				(island_removal_mode 0)
			)
			(polygon
				(pts
					(xy 26.9875 -409.8417) (xy 27.369008 -409.8417) (xy 27.369008 -410.348938) (xy 26.9875 -410.348938)
				)
			)
		)
		(zone
			(layer "F.Cu")
			(hatch none 0.5)
			(connect_pads
				(clearance 0)
			)
			(min_thickness 0.25)
			(keepout
				(tracks not_allowed)
				(vias allowed)
				(pads allowed)
				(copperpour not_allowed)
				(footprints allowed)
			)
			(placement
				(enabled no)
				(sheetname "")
			)
			(fill
				(thermal_gap 0.5)
				(thermal_bridge_width 0.5)
				(island_removal_mode 0)
			)
			(polygon
				(pts
					(xy 26.9875 -409.8417) (xy 27.369008 -409.8417) (xy 27.369008 -410.348938) (xy 26.9875 -410.348938)
				)
			)
		)
	)
)
